(kicad_pcb
	(version 20260206)
	(generator "pcbnew")
	(generator_version "10.0")
	(general
		(thickness 1.6)
		(legacy_teardrops no)
	)
	(paper "A4")
	(title_block
		(title "04192023_DAF0TMB3IC0_F0TG_MB_C_brd_V02_OCP.brd")
		(comment 1 "Grand Teton / footprints 4398-4403 of 8354")
	)
	(layers
		(0 "F.Cu" signal "TOP")
		(4 "In1.Cu" signal "GND")
		(6 "In2.Cu" signal "IN1")
		(8 "In3.Cu" signal "GND1")
		(10 "In4.Cu" signal "IN2")
		(12 "In5.Cu" signal "GND2")
		(14 "In6.Cu" signal "IN3")
		(16 "In7.Cu" signal "GND3")
		(18 "In8.Cu" signal "VCC")
		(20 "In9.Cu" signal "VCC1")
		(22 "In10.Cu" signal "GND4")
		(24 "In11.Cu" signal "IN4")
		(26 "In12.Cu" signal "GND5")
		(28 "In13.Cu" signal "IN5")
		(30 "In14.Cu" signal "GND6")
		(32 "In15.Cu" signal "IN6")
		(34 "In16.Cu" signal "GND7")
		(2 "B.Cu" signal "BOTTOM")
		(9 "F.Adhes" user "F.Adhesive")
		(11 "B.Adhes" user "B.Adhesive")
		(13 "F.Paste" user "Package Geometry/Pastemask Top")
		(15 "B.Paste" user "Package Geometry/Pastemask Bottom")
		(5 "F.SilkS" user "Ref Des/Silkscreen Top")
		(7 "B.SilkS" user "Ref Des/Silkscreen Bottom")
		(1 "F.Mask" user "Board Geometry/Soldermask Top")
		(3 "B.Mask" user "Board Geometry/Soldermask Bottom")
		(17 "Dwgs.User" user "User.Drawings")
		(19 "Cmts.User" user "User.Comments")
		(21 "Eco1.User" user "User.Eco1")
		(23 "Eco2.User" user "User.Eco2")
		(25 "Edge.Cuts" user "Board Geometry/Outline")
		(27 "Margin" user)
		(31 "F.CrtYd" user "Package Geometry/Place Bound Top")
		(29 "B.CrtYd" user "Package Geometry/Place Bound Bottom")
		(35 "F.Fab" user "Ref Des/Assembly Top")
		(33 "B.Fab" user "Ref Des/Assembly Bottom")
	)
	(footprint ""
		(layer "F.Cu")
		(at 49.12868 -29.657548 90)
		(property "Reference" "U286"
			(at -2.56286 -1.925828 90)
			(unlocked yes)
			(layer "F.SilkS")
			(effects
				(font
					(size 0.7874 0.5842)
					(thickness 0.1524)
				)
				(justify left)
			)
		)
		(property "Value" ""
			(at 0 0 90)
			(layer "F.Fab")
			(effects
				(font
					(size 1.27 1.27)
				)
			)
		)
		(duplicate_pad_numbers_are_jumpers no)
		(fp_line
			(start 1.400048 -1.100074)
			(end -1.400048 -1.100074)
			(stroke
				(width 0.1524)
				(type default)
			)
			(layer "F.SilkS")
		)
		(fp_line
			(start 1.400048 -1.100074)
			(end 1.400048 1.100074)
			(stroke
				(width 0.1524)
				(type default)
			)
			(layer "F.SilkS")
		)
		(fp_line
			(start 1.400048 1.100074)
			(end -1.400048 1.100074)
			(stroke
				(width 0.1524)
				(type default)
			)
			(layer "F.SilkS")
		)
		(fp_line
			(start -1.400048 1.100074)
			(end -1.400048 -1.100074)
			(stroke
				(width 0.1524)
				(type default)
			)
			(layer "F.SilkS")
		)
		(fp_poly
			(pts
				(xy -2.606548 -0.141986) (xy -2.606548 -1.157986) (xy -1.590548 -0.649986)
			)
			(stroke
				(width 0)
				(type default)
			)
			(fill yes)
			(layer "F.SilkS")
		)
		(fp_line
			(start 0.674878 -1.100074)
			(end 0.674878 1.100074)
			(stroke
				(width 0.1)
				(type default)
			)
			(layer "F.Fab")
		)
		(fp_line
			(start -0.674878 -1.100074)
			(end 0.674878 -1.100074)
			(stroke
				(width 0.1)
				(type default)
			)
			(layer "F.Fab")
		)
		(fp_line
			(start 0.674878 1.100074)
			(end -0.674878 1.100074)
			(stroke
				(width 0.1)
				(type default)
			)
			(layer "F.Fab")
		)
		(fp_line
			(start -0.674878 1.100074)
			(end -0.674878 -1.100074)
			(stroke
				(width 0.1)
				(type default)
			)
			(layer "F.Fab")
		)
		(fp_poly
			(pts
				(xy -1.590548 -0.649986) (xy -2.606548 -1.157986) (xy -2.606548 -0.141986)
			)
			(stroke
				(width 0)
				(type default)
			)
			(fill yes)
			(layer "F.Fab")
		)
		(pad "1" smd rect
			(at -0.94996 -0.649986)
			(size 0.4318 0.6096)
			(layers "F.Cu" "F.Mask" "F.Paste")
			(net "OCP_V3_2_AUX_PWR_EN_R1")
		)
		(pad "2" smd rect
			(at -0.94996 0)
			(size 0.4318 0.6096)
			(layers "F.Cu" "F.Mask" "F.Paste")
			(net "FM_OCP_V3_2_PWR_GOOD")
		)
		(pad "3" smd rect
			(at -0.94996 0.649986)
			(size 0.4318 0.6096)
			(layers "F.Cu" "F.Mask" "F.Paste")
			(net "GND")
		)
		(pad "4" smd rect
			(at 0.94996 0.649986)
			(size 0.4318 0.6096)
			(layers "F.Cu" "F.Mask" "F.Paste")
			(net "FB_BMC_ISOLATE_R2")
		)
		(pad "5" smd rect
			(at 0.94996 -0.649986)
			(size 0.4318 0.6096)
			(layers "F.Cu" "F.Mask" "F.Paste")
			(net "P3V3_AUX")
		)
	)
	(footprint ""
		(layer "F.Cu")
		(at 236.7661 -402.903182)
		(property "Reference" "PR3995"
			(at 0 0 0)
			(layer "F.SilkS")
			(hide yes)
			(effects
				(font
					(size 1.27 1.27)
				)
			)
		)
		(property "Value" ""
			(at 0 0 0)
			(layer "F.Fab")
			(effects
				(font
					(size 1.27 1.27)
				)
			)
		)
		(duplicate_pad_numbers_are_jumpers no)
		(fp_line
			(start -0.7874 -0.4064)
			(end 0.7874 -0.4064)
			(stroke
				(width 0.1524)
				(type default)
			)
			(layer "F.SilkS")
		)
		(fp_line
			(start -0.7874 0.4064)
			(end -0.7874 -0.4064)
			(stroke
				(width 0.1524)
				(type default)
			)
			(layer "F.SilkS")
		)
		(fp_line
			(start 0.7874 -0.4064)
			(end 0.7874 0.4064)
			(stroke
				(width 0.1524)
				(type default)
			)
			(layer "F.SilkS")
		)
		(fp_line
			(start 0.7874 0.4064)
			(end -0.7874 0.4064)
			(stroke
				(width 0.1524)
				(type default)
			)
			(layer "F.SilkS")
		)
		(fp_line
			(start -0.67945 -0.305054)
			(end -0.12065 -0.305054)
			(stroke
				(width 0.1)
				(type default)
			)
			(layer "F.Fab")
		)
		(fp_line
			(start -0.67945 0.3048)
			(end -0.67945 -0.305054)
			(stroke
				(width 0.1)
				(type default)
			)
			(layer "F.Fab")
		)
		(fp_line
			(start -0.12065 -0.305054)
			(end -0.12065 -0.2794)
			(stroke
				(width 0.1)
				(type default)
			)
			(layer "F.Fab")
		)
		(fp_line
			(start -0.12065 -0.2794)
			(end 0.12065 -0.2794)
			(stroke
				(width 0.1)
				(type default)
			)
			(layer "F.Fab")
		)
		(fp_line
			(start -0.12065 0.2794)
			(end -0.12065 0.3048)
			(stroke
				(width 0.1)
				(type default)
			)
			(layer "F.Fab")
		)
		(fp_line
			(start -0.12065 0.3048)
			(end -0.67945 0.3048)
			(stroke
				(width 0.1)
				(type default)
			)
			(layer "F.Fab")
		)
		(fp_line
			(start 0.120396 0.2794)
			(end -0.12065 0.2794)
			(stroke
				(width 0.1)
				(type default)
			)
			(layer "F.Fab")
		)
		(fp_line
			(start 0.120396 0.3048)
			(end 0.120396 0.2794)
			(stroke
				(width 0.1)
				(type default)
			)
			(layer "F.Fab")
		)
		(fp_line
			(start 0.12065 -0.3048)
			(end 0.67945 -0.3048)
			(stroke
				(width 0.1)
				(type default)
			)
			(layer "F.Fab")
		)
		(fp_line
			(start 0.12065 -0.2794)
			(end 0.12065 -0.3048)
			(stroke
				(width 0.1)
				(type default)
			)
			(layer "F.Fab")
		)
		(fp_line
			(start 0.67945 -0.3048)
			(end 0.67945 0.3048)
			(stroke
				(width 0.1)
				(type default)
			)
			(layer "F.Fab")
		)
		(fp_line
			(start 0.67945 0.3048)
			(end 0.120396 0.3048)
			(stroke
				(width 0.1)
				(type default)
			)
			(layer "F.Fab")
		)
		(pad "1" smd circle
			(at -0.40005 0)
			(size 0 0)
			(layers "F.Cu" "F.Mask" "F.Paste")
			(net "HSC_FLT_TYPE_4")
		)
		(pad "2" smd circle
			(at 0.40005 0)
			(size 0 0)
			(layers "F.Cu" "F.Mask" "F.Paste")
			(net "HSC_FLT_TYPE")
		)
	)
	(footprint ""
		(layer "F.Cu")
		(at 113.899696 -167.2717 90)
		(property "Reference" "PC333"
			(at 0 0 90)
			(layer "F.SilkS")
			(hide yes)
			(effects
				(font
					(size 1.27 1.27)
				)
			)
		)
		(property "Value" ""
			(at 0 0 90)
			(layer "F.Fab")
			(effects
				(font
					(size 1.27 1.27)
				)
			)
		)
		(duplicate_pad_numbers_are_jumpers no)
		(fp_line
			(start 0.7874 -0.4064)
			(end 0.7874 0.4064)
			(stroke
				(width 0.1524)
				(type default)
			)
			(layer "F.SilkS")
		)
		(fp_line
			(start -0.7874 -0.4064)
			(end 0.7874 -0.4064)
			(stroke
				(width 0.1524)
				(type default)
			)
			(layer "F.SilkS")
		)
		(fp_line
			(start 0.7874 0.4064)
			(end -0.7874 0.4064)
			(stroke
				(width 0.1524)
				(type default)
			)
			(layer "F.SilkS")
		)
		(fp_line
			(start -0.7874 0.4064)
			(end -0.7874 -0.4064)
			(stroke
				(width 0.1524)
				(type default)
			)
			(layer "F.SilkS")
		)
		(fp_line
			(start -0.12065 -0.305054)
			(end -0.12065 -0.2794)
			(stroke
				(width 0.1)
				(type default)
			)
			(layer "F.Fab")
		)
		(fp_line
			(start -0.67945 -0.305054)
			(end -0.12065 -0.305054)
			(stroke
				(width 0.1)
				(type default)
			)
			(layer "F.Fab")
		)
		(fp_line
			(start 0.67945 -0.3048)
			(end 0.67945 0.3048)
			(stroke
				(width 0.1)
				(type default)
			)
			(layer "F.Fab")
		)
		(fp_line
			(start 0.12065 -0.3048)
			(end 0.67945 -0.3048)
			(stroke
				(width 0.1)
				(type default)
			)
			(layer "F.Fab")
		)
		(fp_line
			(start 0.12065 -0.2794)
			(end 0.12065 -0.3048)
			(stroke
				(width 0.1)
				(type default)
			)
			(layer "F.Fab")
		)
		(fp_line
			(start -0.12065 -0.2794)
			(end 0.12065 -0.2794)
			(stroke
				(width 0.1)
				(type default)
			)
			(layer "F.Fab")
		)
		(fp_line
			(start 0.120396 0.2794)
			(end -0.12065 0.2794)
			(stroke
				(width 0.1)
				(type default)
			)
			(layer "F.Fab")
		)
		(fp_line
			(start -0.12065 0.2794)
			(end -0.12065 0.3048)
			(stroke
				(width 0.1)
				(type default)
			)
			(layer "F.Fab")
		)
		(fp_line
			(start 0.67945 0.3048)
			(end 0.120396 0.3048)
			(stroke
				(width 0.1)
				(type default)
			)
			(layer "F.Fab")
		)
		(fp_line
			(start 0.120396 0.3048)
			(end 0.120396 0.2794)
			(stroke
				(width 0.1)
				(type default)
			)
			(layer "F.Fab")
		)
		(fp_line
			(start -0.12065 0.3048)
			(end -0.67945 0.3048)
			(stroke
				(width 0.1)
				(type default)
			)
			(layer "F.Fab")
		)
		(fp_line
			(start -0.67945 0.3048)
			(end -0.67945 -0.305054)
			(stroke
				(width 0.1)
				(type default)
			)
			(layer "F.Fab")
		)
		(pad "1" smd circle
			(at -0.40005 0 90)
			(size 0 0)
			(layers "F.Cu" "F.Mask" "F.Paste")
			(net "SW_PVDDCR_SOC_P1_BOOT1_RC")
		)
		(pad "2" smd circle
			(at 0.40005 0 90)
			(size 0 0)
			(layers "F.Cu" "F.Mask" "F.Paste")
			(net "SW_PVDDCR_SOC_P1_PH1")
		)
	)
	(footprint ""
		(layer "F.Cu")
		(at 37.211 -361.061 180)
		(property "Reference" "R8241"
			(at 0 0 180)
			(layer "F.SilkS")
			(hide yes)
			(effects
				(font
					(size 1.27 1.27)
				)
			)
		)
		(property "Value" ""
			(at 0 0 180)
			(layer "F.Fab")
			(effects
				(font
					(size 1.27 1.27)
				)
			)
		)
		(duplicate_pad_numbers_are_jumpers no)
		(fp_line
			(start 0.7874 0.4064)
			(end -0.7874 0.4064)
			(stroke
				(width 0.1524)
				(type default)
			)
			(layer "F.SilkS")
		)
		(fp_line
			(start 0.7874 -0.4064)
			(end 0.7874 0.4064)
			(stroke
				(width 0.1524)
				(type default)
			)
			(layer "F.SilkS")
		)
		(fp_line
			(start -0.7874 0.4064)
			(end -0.7874 -0.4064)
			(stroke
				(width 0.1524)
				(type default)
			)
			(layer "F.SilkS")
		)
		(fp_line
			(start -0.7874 -0.4064)
			(end 0.7874 -0.4064)
			(stroke
				(width 0.1524)
				(type default)
			)
			(layer "F.SilkS")
		)
		(fp_line
			(start 0.67945 0.3048)
			(end 0.120396 0.3048)
			(stroke
				(width 0.1)
				(type default)
			)
			(layer "F.Fab")
		)
		(fp_line
			(start 0.67945 -0.3048)
			(end 0.67945 0.3048)
			(stroke
				(width 0.1)
				(type default)
			)
			(layer "F.Fab")
		)
		(fp_line
			(start 0.12065 -0.2794)
			(end 0.12065 -0.3048)
			(stroke
				(width 0.1)
				(type default)
			)
			(layer "F.Fab")
		)
		(fp_line
			(start 0.12065 -0.3048)
			(end 0.67945 -0.3048)
			(stroke
				(width 0.1)
				(type default)
			)
			(layer "F.Fab")
		)
		(fp_line
			(start 0.120396 0.3048)
			(end 0.120396 0.2794)
			(stroke
				(width 0.1)
				(type default)
			)
			(layer "F.Fab")
		)
		(fp_line
			(start 0.120396 0.2794)
			(end -0.12065 0.2794)
			(stroke
				(width 0.1)
				(type default)
			)
			(layer "F.Fab")
		)
		(fp_line
			(start -0.12065 0.3048)
			(end -0.67945 0.3048)
			(stroke
				(width 0.1)
				(type default)
			)
			(layer "F.Fab")
		)
		(fp_line
			(start -0.12065 0.2794)
			(end -0.12065 0.3048)
			(stroke
				(width 0.1)
				(type default)
			)
			(layer "F.Fab")
		)
		(fp_line
			(start -0.12065 -0.2794)
			(end 0.12065 -0.2794)
			(stroke
				(width 0.1)
				(type default)
			)
			(layer "F.Fab")
		)
		(fp_line
			(start -0.12065 -0.305054)
			(end -0.12065 -0.2794)
			(stroke
				(width 0.1)
				(type default)
			)
			(layer "F.Fab")
		)
		(fp_line
			(start -0.67945 0.3048)
			(end -0.67945 -0.305054)
			(stroke
				(width 0.1)
				(type default)
			)
			(layer "F.Fab")
		)
		(fp_line
			(start -0.67945 -0.305054)
			(end -0.12065 -0.305054)
			(stroke
				(width 0.1)
				(type default)
			)
			(layer "F.Fab")
		)
		(pad "1" smd circle
			(at -0.40005 0 180)
			(size 0 0)
			(layers "F.Cu" "F.Mask" "F.Paste")
			(net "PVDDCR_CPU1_P1_OCP_N")
		)
		(pad "2" smd circle
			(at 0.40005 0 180)
			(size 0 0)
			(layers "F.Cu" "F.Mask" "F.Paste")
			(net "PVDDCR_CPU1_P1_OCP_N_R")
		)
	)
	(footprint ""
		(layer "F.Cu")
		(at 351.4217 -164.14369)
		(property "Reference" "PC182"
			(at 0 0 0)
			(layer "F.SilkS")
			(hide yes)
			(effects
				(font
					(size 1.27 1.27)
				)
			)
		)
		(property "Value" ""
			(at 0 0 0)
			(layer "F.Fab")
			(effects
				(font
					(size 1.27 1.27)
				)
			)
		)
		(duplicate_pad_numbers_are_jumpers no)
		(fp_line
			(start -0.7874 -0.4064)
			(end 0.7874 -0.4064)
			(stroke
				(width 0.1524)
				(type default)
			)
			(layer "F.SilkS")
		)
		(fp_line
			(start -0.7874 0.4064)
			(end -0.7874 -0.4064)
			(stroke
				(width 0.1524)
				(type default)
			)
			(layer "F.SilkS")
		)
		(fp_line
			(start 0.7874 -0.4064)
			(end 0.7874 0.4064)
			(stroke
				(width 0.1524)
				(type default)
			)
			(layer "F.SilkS")
		)
		(fp_line
			(start 0.7874 0.4064)
			(end -0.7874 0.4064)
			(stroke
				(width 0.1524)
				(type default)
			)
			(layer "F.SilkS")
		)
		(fp_line
			(start -0.67945 -0.305054)
			(end -0.12065 -0.305054)
			(stroke
				(width 0.1)
				(type default)
			)
			(layer "F.Fab")
		)
		(fp_line
			(start -0.67945 0.3048)
			(end -0.67945 -0.305054)
			(stroke
				(width 0.1)
				(type default)
			)
			(layer "F.Fab")
		)
		(fp_line
			(start -0.12065 -0.305054)
			(end -0.12065 -0.2794)
			(stroke
				(width 0.1)
				(type default)
			)
			(layer "F.Fab")
		)
		(fp_line
			(start -0.12065 -0.2794)
			(end 0.12065 -0.2794)
			(stroke
				(width 0.1)
				(type default)
			)
			(layer "F.Fab")
		)
		(fp_line
			(start -0.12065 0.2794)
			(end -0.12065 0.3048)
			(stroke
				(width 0.1)
				(type default)
			)
			(layer "F.Fab")
		)
		(fp_line
			(start -0.12065 0.3048)
			(end -0.67945 0.3048)
			(stroke
				(width 0.1)
				(type default)
			)
			(layer "F.Fab")
		)
		(fp_line
			(start 0.120396 0.2794)
			(end -0.12065 0.2794)
			(stroke
				(width 0.1)
				(type default)
			)
			(layer "F.Fab")
		)
		(fp_line
			(start 0.120396 0.3048)
			(end 0.120396 0.2794)
			(stroke
				(width 0.1)
				(type default)
			)
			(layer "F.Fab")
		)
		(fp_line
			(start 0.12065 -0.3048)
			(end 0.67945 -0.3048)
			(stroke
				(width 0.1)
				(type default)
			)
			(layer "F.Fab")
		)
		(fp_line
			(start 0.12065 -0.2794)
			(end 0.12065 -0.3048)
			(stroke
				(width 0.1)
				(type default)
			)
			(layer "F.Fab")
		)
		(fp_line
			(start 0.67945 -0.3048)
			(end 0.67945 0.3048)
			(stroke
				(width 0.1)
				(type default)
			)
			(layer "F.Fab")
		)
		(fp_line
			(start 0.67945 0.3048)
			(end 0.120396 0.3048)
			(stroke
				(width 0.1)
				(type default)
			)
			(layer "F.Fab")
		)
		(pad "1" smd circle
			(at -0.40005 0)
			(size 0 0)
			(layers "F.Cu" "F.Mask" "F.Paste")
			(net "SW_PVDDCR_CPU0_P0_SW6")
		)
		(pad "2" smd circle
			(at 0.40005 0)
			(size 0 0)
			(layers "F.Cu" "F.Mask" "F.Paste")
			(net "SW_PVDDCR_CPU0_P0_SW6_RC")
		)
	)
	(footprint ""
		(layer "F.Cu")
		(at 71.663814 -145.801588 180)
		(property "Reference" "PC6006"
			(at 0 0 180)
			(layer "F.SilkS")
			(hide yes)
			(effects
				(font
					(size 1.27 1.27)
				)
			)
		)
		(property "Value" ""
			(at 0 0 180)
			(layer "F.Fab")
			(effects
				(font
					(size 1.27 1.27)
				)
			)
		)
		(duplicate_pad_numbers_are_jumpers no)
		(fp_line
			(start 0.7874 0.4064)
			(end -0.7874 0.4064)
			(stroke
				(width 0.1524)
				(type default)
			)
			(layer "F.SilkS")
		)
		(fp_line
			(start 0.7874 -0.4064)
			(end 0.7874 0.4064)
			(stroke
				(width 0.1524)
				(type default)
			)
			(layer "F.SilkS")
		)
		(fp_line
			(start -0.7874 0.4064)
			(end -0.7874 -0.4064)
			(stroke
				(width 0.1524)
				(type default)
			)
			(layer "F.SilkS")
		)
		(fp_line
			(start -0.7874 -0.4064)
			(end 0.7874 -0.4064)
			(stroke
				(width 0.1524)
				(type default)
			)
			(layer "F.SilkS")
		)
		(fp_line
			(start 0.67945 0.3048)
			(end 0.120396 0.3048)
			(stroke
				(width 0.1)
				(type default)
			)
			(layer "F.Fab")
		)
		(fp_line
			(start 0.67945 -0.3048)
			(end 0.67945 0.3048)
			(stroke
				(width 0.1)
				(type default)
			)
			(layer "F.Fab")
		)
		(fp_line
			(start 0.12065 -0.2794)
			(end 0.12065 -0.3048)
			(stroke
				(width 0.1)
				(type default)
			)
			(layer "F.Fab")
		)
		(fp_line
			(start 0.12065 -0.3048)
			(end 0.67945 -0.3048)
			(stroke
				(width 0.1)
				(type default)
			)
			(layer "F.Fab")
		)
		(fp_line
			(start 0.120396 0.3048)
			(end 0.120396 0.2794)
			(stroke
				(width 0.1)
				(type default)
			)
			(layer "F.Fab")
		)
		(fp_line
			(start 0.120396 0.2794)
			(end -0.12065 0.2794)
			(stroke
				(width 0.1)
				(type default)
			)
			(layer "F.Fab")
		)
		(fp_line
			(start -0.12065 0.3048)
			(end -0.67945 0.3048)
			(stroke
				(width 0.1)
				(type default)
			)
			(layer "F.Fab")
		)
		(fp_line
			(start -0.12065 0.2794)
			(end -0.12065 0.3048)
			(stroke
				(width 0.1)
				(type default)
			)
			(layer "F.Fab")
		)
		(fp_line
			(start -0.12065 -0.2794)
			(end 0.12065 -0.2794)
			(stroke
				(width 0.1)
				(type default)
			)
			(layer "F.Fab")
		)
		(fp_line
			(start -0.12065 -0.305054)
			(end -0.12065 -0.2794)
			(stroke
				(width 0.1)
				(type default)
			)
			(layer "F.Fab")
		)
		(fp_line
			(start -0.67945 0.3048)
			(end -0.67945 -0.305054)
			(stroke
				(width 0.1)
				(type default)
			)
			(layer "F.Fab")
		)
		(fp_line
			(start -0.67945 -0.305054)
			(end -0.12065 -0.305054)
			(stroke
				(width 0.1)
				(type default)
			)
			(layer "F.Fab")
		)
		(pad "1" smd circle
			(at -0.40005 0 180)
			(size 0 0)
			(layers "F.Cu" "F.Mask" "F.Paste")
			(net "PVDD18_S5_P1_FB_RC")
		)
		(pad "2" smd circle
			(at 0.40005 0 180)
			(size 0 0)
			(layers "F.Cu" "F.Mask" "F.Paste")
			(net "PVDD18_SS_P1_RGND")
		)
	)
)
